(kicad_pcb
	(version 20260206)
	(generator "pcbnew")
	(generator_version "10.0")
	(general
		(thickness 1.6)
		(legacy_teardrops no)
	)
	(paper "A4")
	(title_block
		(title "01162023_DA0F0TEBIF0_F0T_Expander_BD_F_brd_V02_OCP.brd")
		(comment 1 "Grand Teton / footprints 924-930 of 9728")
	)
	(layers
		(0 "F.Cu" signal "TOP")
		(4 "In1.Cu" signal "GND")
		(6 "In2.Cu" signal "VCC")
		(8 "In3.Cu" signal "VCC1")
		(10 "In4.Cu" signal "GND1")
		(12 "In5.Cu" signal "IN1")
		(14 "In6.Cu" signal "GND2")
		(16 "In7.Cu" signal "IN2")
		(18 "In8.Cu" signal "GND3")
		(20 "In9.Cu" signal "IN3")
		(22 "In10.Cu" signal "GND4")
		(24 "In11.Cu" signal "IN4")
		(26 "In12.Cu" signal "GND5")
		(28 "In13.Cu" signal "IN5")
		(30 "In14.Cu" signal "GND6")
		(32 "In15.Cu" signal "IN6")
		(34 "In16.Cu" signal "GND7")
		(2 "B.Cu" signal "BOTTOM")
		(9 "F.Adhes" user "F.Adhesive")
		(11 "B.Adhes" user "B.Adhesive")
		(13 "F.Paste" user "Package Geometry/Pastemask Top")
		(15 "B.Paste" user "Package Geometry/Pastemask Bottom")
		(5 "F.SilkS" user "Ref Des/Silkscreen Top")
		(7 "B.SilkS" user "Ref Des/Silkscreen Bottom")
		(1 "F.Mask" user "Board Geometry/Soldermask Top")
		(3 "B.Mask" user "Board Geometry/Soldermask Bottom")
		(17 "Dwgs.User" user "User.Drawings")
		(19 "Cmts.User" user "User.Comments")
		(21 "Eco1.User" user "User.Eco1")
		(23 "Eco2.User" user "User.Eco2")
		(25 "Edge.Cuts" user "Board Geometry/Outline")
		(27 "Margin" user)
		(31 "F.CrtYd" user "Package Geometry/Place Bound Top")
		(29 "B.CrtYd" user "Package Geometry/Place Bound Bottom")
		(35 "F.Fab" user "Ref Des/Assembly Top")
		(33 "B.Fab" user "Ref Des/Assembly Bottom")
	)
	(footprint ""
		(layer "F.Cu")
		(at 287.075118 -63.086234)
		(property "Reference" "R6008"
			(at 0 0 0)
			(layer "F.SilkS")
			(hide yes)
			(effects
				(font
					(size 1.27 1.27)
				)
			)
		)
		(property "Value" ""
			(at 0 0 0)
			(layer "F.Fab")
			(effects
				(font
					(size 1.27 1.27)
				)
			)
		)
		(duplicate_pad_numbers_are_jumpers no)
		(fp_line
			(start -0.7874 -0.4064)
			(end 0.7874 -0.4064)
			(stroke
				(width 0.1524)
				(type default)
			)
			(layer "F.SilkS")
		)
		(fp_line
			(start -0.7874 0.4064)
			(end -0.7874 -0.4064)
			(stroke
				(width 0.1524)
				(type default)
			)
			(layer "F.SilkS")
		)
		(fp_line
			(start 0.7874 -0.4064)
			(end 0.7874 0.4064)
			(stroke
				(width 0.1524)
				(type default)
			)
			(layer "F.SilkS")
		)
		(fp_line
			(start 0.7874 0.4064)
			(end -0.7874 0.4064)
			(stroke
				(width 0.1524)
				(type default)
			)
			(layer "F.SilkS")
		)
		(fp_line
			(start -0.67945 -0.305054)
			(end -0.12065 -0.305054)
			(stroke
				(width 0.1)
				(type default)
			)
			(layer "F.Fab")
		)
		(fp_line
			(start -0.67945 0.3048)
			(end -0.67945 -0.305054)
			(stroke
				(width 0.1)
				(type default)
			)
			(layer "F.Fab")
		)
		(fp_line
			(start -0.12065 -0.305054)
			(end -0.12065 -0.2794)
			(stroke
				(width 0.1)
				(type default)
			)
			(layer "F.Fab")
		)
		(fp_line
			(start -0.12065 -0.2794)
			(end 0.12065 -0.2794)
			(stroke
				(width 0.1)
				(type default)
			)
			(layer "F.Fab")
		)
		(fp_line
			(start -0.12065 0.2794)
			(end -0.12065 0.3048)
			(stroke
				(width 0.1)
				(type default)
			)
			(layer "F.Fab")
		)
		(fp_line
			(start -0.12065 0.3048)
			(end -0.67945 0.3048)
			(stroke
				(width 0.1)
				(type default)
			)
			(layer "F.Fab")
		)
		(fp_line
			(start 0.120396 0.2794)
			(end -0.12065 0.2794)
			(stroke
				(width 0.1)
				(type default)
			)
			(layer "F.Fab")
		)
		(fp_line
			(start 0.120396 0.3048)
			(end 0.120396 0.2794)
			(stroke
				(width 0.1)
				(type default)
			)
			(layer "F.Fab")
		)
		(fp_line
			(start 0.12065 -0.3048)
			(end 0.67945 -0.3048)
			(stroke
				(width 0.1)
				(type default)
			)
			(layer "F.Fab")
		)
		(fp_line
			(start 0.12065 -0.2794)
			(end 0.12065 -0.3048)
			(stroke
				(width 0.1)
				(type default)
			)
			(layer "F.Fab")
		)
		(fp_line
			(start 0.67945 -0.3048)
			(end 0.67945 0.3048)
			(stroke
				(width 0.1)
				(type default)
			)
			(layer "F.Fab")
		)
		(fp_line
			(start 0.67945 0.3048)
			(end 0.120396 0.3048)
			(stroke
				(width 0.1)
				(type default)
			)
			(layer "F.Fab")
		)
		(pad "1" smd circle
			(at -0.40005 0)
			(size 0 0)
			(layers "F.Cu" "F.Mask" "F.Paste")
			(net "P12V_SSD10_R")
		)
		(pad "2" smd circle
			(at 0.40005 0)
			(size 0 0)
			(layers "F.Cu" "F.Mask" "F.Paste")
			(net "P12V_SSD10_PG_G1")
		)
	)
	(footprint ""
		(layer "F.Cu")
		(at 378.738384 -252.356874 -90)
		(property "Reference" "R1425"
			(at 0 0 270)
			(layer "F.SilkS")
			(hide yes)
			(effects
				(font
					(size 1.27 1.27)
				)
			)
		)
		(property "Value" ""
			(at 0 0 270)
			(layer "F.Fab")
			(effects
				(font
					(size 1.27 1.27)
				)
			)
		)
		(duplicate_pad_numbers_are_jumpers no)
		(fp_line
			(start -0.7874 0.4064)
			(end -0.7874 -0.4064)
			(stroke
				(width 0.1524)
				(type default)
			)
			(layer "F.SilkS")
		)
		(fp_line
			(start 0.7874 0.4064)
			(end -0.7874 0.4064)
			(stroke
				(width 0.1524)
				(type default)
			)
			(layer "F.SilkS")
		)
		(fp_line
			(start -0.7874 -0.4064)
			(end 0.7874 -0.4064)
			(stroke
				(width 0.1524)
				(type default)
			)
			(layer "F.SilkS")
		)
		(fp_line
			(start 0.7874 -0.4064)
			(end 0.7874 0.4064)
			(stroke
				(width 0.1524)
				(type default)
			)
			(layer "F.SilkS")
		)
		(fp_line
			(start -0.67945 0.3048)
			(end -0.67945 -0.305054)
			(stroke
				(width 0.1)
				(type default)
			)
			(layer "F.Fab")
		)
		(fp_line
			(start -0.12065 0.3048)
			(end -0.67945 0.3048)
			(stroke
				(width 0.1)
				(type default)
			)
			(layer "F.Fab")
		)
		(fp_line
			(start 0.120396 0.3048)
			(end 0.120396 0.2794)
			(stroke
				(width 0.1)
				(type default)
			)
			(layer "F.Fab")
		)
		(fp_line
			(start 0.67945 0.3048)
			(end 0.120396 0.3048)
			(stroke
				(width 0.1)
				(type default)
			)
			(layer "F.Fab")
		)
		(fp_line
			(start -0.12065 0.2794)
			(end -0.12065 0.3048)
			(stroke
				(width 0.1)
				(type default)
			)
			(layer "F.Fab")
		)
		(fp_line
			(start 0.120396 0.2794)
			(end -0.12065 0.2794)
			(stroke
				(width 0.1)
				(type default)
			)
			(layer "F.Fab")
		)
		(fp_line
			(start -0.12065 -0.2794)
			(end 0.12065 -0.2794)
			(stroke
				(width 0.1)
				(type default)
			)
			(layer "F.Fab")
		)
		(fp_line
			(start 0.12065 -0.2794)
			(end 0.12065 -0.3048)
			(stroke
				(width 0.1)
				(type default)
			)
			(layer "F.Fab")
		)
		(fp_line
			(start 0.12065 -0.3048)
			(end 0.67945 -0.3048)
			(stroke
				(width 0.1)
				(type default)
			)
			(layer "F.Fab")
		)
		(fp_line
			(start 0.67945 -0.3048)
			(end 0.67945 0.3048)
			(stroke
				(width 0.1)
				(type default)
			)
			(layer "F.Fab")
		)
		(fp_line
			(start -0.67945 -0.305054)
			(end -0.12065 -0.305054)
			(stroke
				(width 0.1)
				(type default)
			)
			(layer "F.Fab")
		)
		(fp_line
			(start -0.12065 -0.305054)
			(end -0.12065 -0.2794)
			(stroke
				(width 0.1)
				(type default)
			)
			(layer "F.Fab")
		)
		(pad "1" smd circle
			(at -0.40005 0 270)
			(size 0 0)
			(layers "F.Cu" "F.Mask" "F.Paste")
			(net "GND")
		)
		(pad "2" smd circle
			(at 0.40005 0 270)
			(size 0 0)
			(layers "F.Cu" "F.Mask" "F.Paste")
			(net "PEX3_MODE_SEL0")
		)
	)
	(footprint ""
		(layer "F.Cu")
		(at 154.707844 -159.4104 180)
		(property "Reference" "R104"
			(at 0 0 180)
			(layer "F.SilkS")
			(hide yes)
			(effects
				(font
					(size 1.27 1.27)
				)
			)
		)
		(property "Value" ""
			(at 0 0 180)
			(layer "F.Fab")
			(effects
				(font
					(size 1.27 1.27)
				)
			)
		)
		(duplicate_pad_numbers_are_jumpers no)
		(fp_line
			(start 0.7874 0.4064)
			(end -0.7874 0.4064)
			(stroke
				(width 0.1524)
				(type default)
			)
			(layer "F.SilkS")
		)
		(fp_line
			(start 0.7874 -0.4064)
			(end 0.7874 0.4064)
			(stroke
				(width 0.1524)
				(type default)
			)
			(layer "F.SilkS")
		)
		(fp_line
			(start -0.7874 0.4064)
			(end -0.7874 -0.4064)
			(stroke
				(width 0.1524)
				(type default)
			)
			(layer "F.SilkS")
		)
		(fp_line
			(start -0.7874 -0.4064)
			(end 0.7874 -0.4064)
			(stroke
				(width 0.1524)
				(type default)
			)
			(layer "F.SilkS")
		)
		(fp_line
			(start 0.67945 0.3048)
			(end 0.120396 0.3048)
			(stroke
				(width 0.1)
				(type default)
			)
			(layer "F.Fab")
		)
		(fp_line
			(start 0.67945 -0.3048)
			(end 0.67945 0.3048)
			(stroke
				(width 0.1)
				(type default)
			)
			(layer "F.Fab")
		)
		(fp_line
			(start 0.12065 -0.2794)
			(end 0.12065 -0.3048)
			(stroke
				(width 0.1)
				(type default)
			)
			(layer "F.Fab")
		)
		(fp_line
			(start 0.12065 -0.3048)
			(end 0.67945 -0.3048)
			(stroke
				(width 0.1)
				(type default)
			)
			(layer "F.Fab")
		)
		(fp_line
			(start 0.120396 0.3048)
			(end 0.120396 0.2794)
			(stroke
				(width 0.1)
				(type default)
			)
			(layer "F.Fab")
		)
		(fp_line
			(start 0.120396 0.2794)
			(end -0.12065 0.2794)
			(stroke
				(width 0.1)
				(type default)
			)
			(layer "F.Fab")
		)
		(fp_line
			(start -0.12065 0.3048)
			(end -0.67945 0.3048)
			(stroke
				(width 0.1)
				(type default)
			)
			(layer "F.Fab")
		)
		(fp_line
			(start -0.12065 0.2794)
			(end -0.12065 0.3048)
			(stroke
				(width 0.1)
				(type default)
			)
			(layer "F.Fab")
		)
		(fp_line
			(start -0.12065 -0.2794)
			(end 0.12065 -0.2794)
			(stroke
				(width 0.1)
				(type default)
			)
			(layer "F.Fab")
		)
		(fp_line
			(start -0.12065 -0.305054)
			(end -0.12065 -0.2794)
			(stroke
				(width 0.1)
				(type default)
			)
			(layer "F.Fab")
		)
		(fp_line
			(start -0.67945 0.3048)
			(end -0.67945 -0.305054)
			(stroke
				(width 0.1)
				(type default)
			)
			(layer "F.Fab")
		)
		(fp_line
			(start -0.67945 -0.305054)
			(end -0.12065 -0.305054)
			(stroke
				(width 0.1)
				(type default)
			)
			(layer "F.Fab")
		)
		(pad "1" smd circle
			(at -0.40005 0 180)
			(size 0 0)
			(layers "F.Cu" "F.Mask" "F.Paste")
			(net "NIC2_MAIN_PWR_EN_R")
		)
		(pad "2" smd circle
			(at 0.40005 0 180)
			(size 0 0)
			(layers "F.Cu" "F.Mask" "F.Paste")
			(net "NIC2_MAIN_PWR_EN")
		)
	)
	(footprint ""
		(layer "F.Cu")
		(at 240.24971 -159.844994 180)
		(property "Reference" "PR7028"
			(at 0 0 180)
			(layer "F.SilkS")
			(hide yes)
			(effects
				(font
					(size 1.27 1.27)
				)
			)
		)
		(property "Value" ""
			(at 0 0 180)
			(layer "F.Fab")
			(effects
				(font
					(size 1.27 1.27)
				)
			)
		)
		(duplicate_pad_numbers_are_jumpers no)
		(fp_line
			(start 0.7874 0.4064)
			(end -0.7874 0.4064)
			(stroke
				(width 0.1524)
				(type default)
			)
			(layer "F.SilkS")
		)
		(fp_line
			(start 0.7874 -0.4064)
			(end 0.7874 0.4064)
			(stroke
				(width 0.1524)
				(type default)
			)
			(layer "F.SilkS")
		)
		(fp_line
			(start -0.7874 0.4064)
			(end -0.7874 -0.4064)
			(stroke
				(width 0.1524)
				(type default)
			)
			(layer "F.SilkS")
		)
		(fp_line
			(start -0.7874 -0.4064)
			(end 0.7874 -0.4064)
			(stroke
				(width 0.1524)
				(type default)
			)
			(layer "F.SilkS")
		)
		(fp_line
			(start 0.67945 0.3048)
			(end 0.120396 0.3048)
			(stroke
				(width 0.1)
				(type default)
			)
			(layer "F.Fab")
		)
		(fp_line
			(start 0.67945 -0.3048)
			(end 0.67945 0.3048)
			(stroke
				(width 0.1)
				(type default)
			)
			(layer "F.Fab")
		)
		(fp_line
			(start 0.12065 -0.2794)
			(end 0.12065 -0.3048)
			(stroke
				(width 0.1)
				(type default)
			)
			(layer "F.Fab")
		)
		(fp_line
			(start 0.12065 -0.3048)
			(end 0.67945 -0.3048)
			(stroke
				(width 0.1)
				(type default)
			)
			(layer "F.Fab")
		)
		(fp_line
			(start 0.120396 0.3048)
			(end 0.120396 0.2794)
			(stroke
				(width 0.1)
				(type default)
			)
			(layer "F.Fab")
		)
		(fp_line
			(start 0.120396 0.2794)
			(end -0.12065 0.2794)
			(stroke
				(width 0.1)
				(type default)
			)
			(layer "F.Fab")
		)
		(fp_line
			(start -0.12065 0.3048)
			(end -0.67945 0.3048)
			(stroke
				(width 0.1)
				(type default)
			)
			(layer "F.Fab")
		)
		(fp_line
			(start -0.12065 0.2794)
			(end -0.12065 0.3048)
			(stroke
				(width 0.1)
				(type default)
			)
			(layer "F.Fab")
		)
		(fp_line
			(start -0.12065 -0.2794)
			(end 0.12065 -0.2794)
			(stroke
				(width 0.1)
				(type default)
			)
			(layer "F.Fab")
		)
		(fp_line
			(start -0.12065 -0.305054)
			(end -0.12065 -0.2794)
			(stroke
				(width 0.1)
				(type default)
			)
			(layer "F.Fab")
		)
		(fp_line
			(start -0.67945 0.3048)
			(end -0.67945 -0.305054)
			(stroke
				(width 0.1)
				(type default)
			)
			(layer "F.Fab")
		)
		(fp_line
			(start -0.67945 -0.305054)
			(end -0.12065 -0.305054)
			(stroke
				(width 0.1)
				(type default)
			)
			(layer "F.Fab")
		)
		(pad "1" smd circle
			(at -0.40005 0 180)
			(size 0 0)
			(layers "F.Cu" "F.Mask" "F.Paste")
			(net "P12V_NIC4_CO_FLTB")
		)
		(pad "2" smd circle
			(at 0.40005 0 180)
			(size 0 0)
			(layers "F.Cu" "F.Mask" "F.Paste")
			(net "P3V3_AUX")
		)
	)
	(footprint ""
		(layer "F.Cu")
		(at 217.767916 -19.453098)
		(property "Reference" "R1682"
			(at 0 0 0)
			(layer "F.SilkS")
			(hide yes)
			(effects
				(font
					(size 1.27 1.27)
				)
			)
		)
		(property "Value" ""
			(at 0 0 0)
			(layer "F.Fab")
			(effects
				(font
					(size 1.27 1.27)
				)
			)
		)
		(duplicate_pad_numbers_are_jumpers no)
		(fp_line
			(start -0.7874 -0.4064)
			(end 0.7874 -0.4064)
			(stroke
				(width 0.1524)
				(type default)
			)
			(layer "F.SilkS")
		)
		(fp_line
			(start -0.7874 0.4064)
			(end -0.7874 -0.4064)
			(stroke
				(width 0.1524)
				(type default)
			)
			(layer "F.SilkS")
		)
		(fp_line
			(start 0.7874 -0.4064)
			(end 0.7874 0.4064)
			(stroke
				(width 0.1524)
				(type default)
			)
			(layer "F.SilkS")
		)
		(fp_line
			(start 0.7874 0.4064)
			(end -0.7874 0.4064)
			(stroke
				(width 0.1524)
				(type default)
			)
			(layer "F.SilkS")
		)
		(fp_line
			(start -0.67945 -0.305054)
			(end -0.12065 -0.305054)
			(stroke
				(width 0.1)
				(type default)
			)
			(layer "F.Fab")
		)
		(fp_line
			(start -0.67945 0.3048)
			(end -0.67945 -0.305054)
			(stroke
				(width 0.1)
				(type default)
			)
			(layer "F.Fab")
		)
		(fp_line
			(start -0.12065 -0.305054)
			(end -0.12065 -0.2794)
			(stroke
				(width 0.1)
				(type default)
			)
			(layer "F.Fab")
		)
		(fp_line
			(start -0.12065 -0.2794)
			(end 0.12065 -0.2794)
			(stroke
				(width 0.1)
				(type default)
			)
			(layer "F.Fab")
		)
		(fp_line
			(start -0.12065 0.2794)
			(end -0.12065 0.3048)
			(stroke
				(width 0.1)
				(type default)
			)
			(layer "F.Fab")
		)
		(fp_line
			(start -0.12065 0.3048)
			(end -0.67945 0.3048)
			(stroke
				(width 0.1)
				(type default)
			)
			(layer "F.Fab")
		)
		(fp_line
			(start 0.120396 0.2794)
			(end -0.12065 0.2794)
			(stroke
				(width 0.1)
				(type default)
			)
			(layer "F.Fab")
		)
		(fp_line
			(start 0.120396 0.3048)
			(end 0.120396 0.2794)
			(stroke
				(width 0.1)
				(type default)
			)
			(layer "F.Fab")
		)
		(fp_line
			(start 0.12065 -0.3048)
			(end 0.67945 -0.3048)
			(stroke
				(width 0.1)
				(type default)
			)
			(layer "F.Fab")
		)
		(fp_line
			(start 0.12065 -0.2794)
			(end 0.12065 -0.3048)
			(stroke
				(width 0.1)
				(type default)
			)
			(layer "F.Fab")
		)
		(fp_line
			(start 0.67945 -0.3048)
			(end 0.67945 0.3048)
			(stroke
				(width 0.1)
				(type default)
			)
			(layer "F.Fab")
		)
		(fp_line
			(start 0.67945 0.3048)
			(end 0.120396 0.3048)
			(stroke
				(width 0.1)
				(type default)
			)
			(layer "F.Fab")
		)
		(pad "1" smd circle
			(at -0.40005 0)
			(size 0 0)
			(layers "F.Cu" "F.Mask" "F.Paste")
			(net "SMB_ISO_SSD7_R_SDA")
		)
		(pad "2" smd circle
			(at 0.40005 0)
			(size 0 0)
			(layers "F.Cu" "F.Mask" "F.Paste")
			(net "SMB_ISO_SSD7_SDA")
		)
	)
	(footprint ""
		(layer "F.Cu")
		(at 98.434398 -30.03169 180)
		(property "Reference" "C94"
			(at 0 0 180)
			(layer "F.SilkS")
			(hide yes)
			(effects
				(font
					(size 1.27 1.27)
				)
			)
		)
		(property "Value" ""
			(at 0 0 180)
			(layer "F.Fab")
			(effects
				(font
					(size 1.27 1.27)
				)
			)
		)
		(duplicate_pad_numbers_are_jumpers no)
		(fp_line
			(start 0.299974 0.150114)
			(end -0.299974 0.150114)
			(stroke
				(width 0.1)
				(type default)
			)
			(layer "F.Fab")
		)
		(fp_line
			(start 0.299974 -0.150114)
			(end 0.299974 0.150114)
			(stroke
				(width 0.1)
				(type default)
			)
			(layer "F.Fab")
		)
		(fp_line
			(start -0.299974 0.150114)
			(end -0.299974 -0.150114)
			(stroke
				(width 0.1)
				(type default)
			)
			(layer "F.Fab")
		)
		(fp_line
			(start -0.299974 -0.150114)
			(end 0.299974 -0.150114)
			(stroke
				(width 0.1)
				(type default)
			)
			(layer "F.Fab")
		)
		(pad "1" smd rect
			(at -0.2667 0 180)
			(size 0.3048 0.381)
			(layers "F.Cu" "F.Mask" "F.Paste")
			(net "P5E_PEX0_STN2_TX_DN<33>")
		)
		(pad "2" smd rect
			(at 0.2667 0 180)
			(size 0.3048 0.381)
			(layers "F.Cu" "F.Mask" "F.Paste")
			(net "P5E_PEX0_STN2_TX_C_DN<33>")
		)
	)
	(footprint ""
		(layer "F.Cu")
		(at 437.30164 -304.036476 90)
		(property "Reference" "R1450"
			(at 0 0 90)
			(layer "F.SilkS")
			(hide yes)
			(effects
				(font
					(size 1.27 1.27)
				)
			)
		)
		(property "Value" ""
			(at 0 0 90)
			(layer "F.Fab")
			(effects
				(font
					(size 1.27 1.27)
				)
			)
		)
		(duplicate_pad_numbers_are_jumpers no)
		(fp_line
			(start 0.7874 -0.4064)
			(end 0.7874 0.4064)
			(stroke
				(width 0.1524)
				(type default)
			)
			(layer "F.SilkS")
		)
		(fp_line
			(start -0.7874 -0.4064)
			(end 0.7874 -0.4064)
			(stroke
				(width 0.1524)
				(type default)
			)
			(layer "F.SilkS")
		)
		(fp_line
			(start 0.7874 0.4064)
			(end -0.7874 0.4064)
			(stroke
				(width 0.1524)
				(type default)
			)
			(layer "F.SilkS")
		)
		(fp_line
			(start -0.7874 0.4064)
			(end -0.7874 -0.4064)
			(stroke
				(width 0.1524)
				(type default)
			)
			(layer "F.SilkS")
		)
		(fp_line
			(start -0.12065 -0.305054)
			(end -0.12065 -0.2794)
			(stroke
				(width 0.1)
				(type default)
			)
			(layer "F.Fab")
		)
		(fp_line
			(start -0.67945 -0.305054)
			(end -0.12065 -0.305054)
			(stroke
				(width 0.1)
				(type default)
			)
			(layer "F.Fab")
		)
		(fp_line
			(start 0.67945 -0.3048)
			(end 0.67945 0.3048)
			(stroke
				(width 0.1)
				(type default)
			)
			(layer "F.Fab")
		)
		(fp_line
			(start 0.12065 -0.3048)
			(end 0.67945 -0.3048)
			(stroke
				(width 0.1)
				(type default)
			)
			(layer "F.Fab")
		)
		(fp_line
			(start 0.12065 -0.2794)
			(end 0.12065 -0.3048)
			(stroke
				(width 0.1)
				(type default)
			)
			(layer "F.Fab")
		)
		(fp_line
			(start -0.12065 -0.2794)
			(end 0.12065 -0.2794)
			(stroke
				(width 0.1)
				(type default)
			)
			(layer "F.Fab")
		)
		(fp_line
			(start 0.120396 0.2794)
			(end -0.12065 0.2794)
			(stroke
				(width 0.1)
				(type default)
			)
			(layer "F.Fab")
		)
		(fp_line
			(start -0.12065 0.2794)
			(end -0.12065 0.3048)
			(stroke
				(width 0.1)
				(type default)
			)
			(layer "F.Fab")
		)
		(fp_line
			(start 0.67945 0.3048)
			(end 0.120396 0.3048)
			(stroke
				(width 0.1)
				(type default)
			)
			(layer "F.Fab")
		)
		(fp_line
			(start 0.120396 0.3048)
			(end 0.120396 0.2794)
			(stroke
				(width 0.1)
				(type default)
			)
			(layer "F.Fab")
		)
		(fp_line
			(start -0.12065 0.3048)
			(end -0.67945 0.3048)
			(stroke
				(width 0.1)
				(type default)
			)
			(layer "F.Fab")
		)
		(fp_line
			(start -0.67945 0.3048)
			(end -0.67945 -0.305054)
			(stroke
				(width 0.1)
				(type default)
			)
			(layer "F.Fab")
		)
		(pad "1" smd circle
			(at -0.40005 0 90)
			(size 0 0)
			(layers "F.Cu" "F.Mask" "F.Paste")
			(net "GND")
		)
		(pad "2" smd circle
			(at 0.40005 0 90)
			(size 0 0)
			(layers "F.Cu" "F.Mask" "F.Paste")
			(net "PEX3_SPARE4")
		)
	)
)
